# T6G (Grand Teton) — schematic netlist excerpt (pin names and nets, part order shuffled) for the footprints in the layout excerpt that follows; sources: Cadence DE-HDL packaged netlist, KiCad conversion of 04192023_DAF0TMB3IC0_F0TG_MB_C_brd_V02_OCP.brd

U154  SN74AUC2G66DCTR  IC  pkg SSOP8  page 174
  \1a\  = JTAG_CPU1_TDO
  \1b\  = JTAG_CPUX_TDO_R
  \2c\  = FM_PLD_CPU1_PRSNT_HDT_N
  GND  = GND
  \2a\  = JTAG_CPU1_BYPASS
  \2b\  = JTAG_CPUX_TDO_R
  \1c\  = CPU1_HDT_BYPASS_SEL
  VCC  = PVDD18_S5_P0

PC176_10  Q_CAP  0.1UF 25V 10% X7R  pkg 0402  page 206 : A = PVDDCR_CPU1_P0_VCCS ; B = GND

(kicad_pcb
	(version 20260206)
	(generator "pcbnew")
	(generator_version "10.0")
	(general
		(thickness 1.6)
		(legacy_teardrops no)
	)
	(paper "A4")
	(title_block
		(title "04192023_DAF0TMB3IC0_F0TG_MB_C_brd_V02_OCP.brd")
		(comment 1 "Grand Teton / footprints 1433-1434 of 8354")
	)
	(layers
		(0 "F.Cu" signal "TOP")
		(4 "In1.Cu" signal "GND")
		(6 "In2.Cu" signal "IN1")
		(8 "In3.Cu" signal "GND1")
		(10 "In4.Cu" signal "IN2")
		(12 "In5.Cu" signal "GND2")
		(14 "In6.Cu" signal "IN3")
		(16 "In7.Cu" signal "GND3")
		(18 "In8.Cu" signal "VCC")
		(20 "In9.Cu" signal "VCC1")
		(22 "In10.Cu" signal "GND4")
		(24 "In11.Cu" signal "IN4")
		(26 "In12.Cu" signal "GND5")
		(28 "In13.Cu" signal "IN5")
		(30 "In14.Cu" signal "GND6")
		(32 "In15.Cu" signal "IN6")
		(34 "In16.Cu" signal "GND7")
		(2 "B.Cu" signal "BOTTOM")
		(9 "F.Adhes" user "F.Adhesive")
		(11 "B.Adhes" user "B.Adhesive")
		(13 "F.Paste" user "Package Geometry/Pastemask Top")
		(15 "B.Paste" user "Package Geometry/Pastemask Bottom")
		(5 "F.SilkS" user "Ref Des/Silkscreen Top")
		(7 "B.SilkS" user "Ref Des/Silkscreen Bottom")
		(1 "F.Mask" user "Board Geometry/Soldermask Top")
		(3 "B.Mask" user "Board Geometry/Soldermask Bottom")
		(17 "Dwgs.User" user "User.Drawings")
		(19 "Cmts.User" user "User.Comments")
		(21 "Eco1.User" user "User.Eco1")
		(23 "Eco2.User" user "User.Eco2")
		(25 "Edge.Cuts" user "Board Geometry/Outline")
		(27 "Margin" user)
		(31 "F.CrtYd" user "Package Geometry/Place Bound Top")
		(29 "B.CrtYd" user "Package Geometry/Place Bound Bottom")
		(35 "F.Fab" user "Ref Des/Assembly Top")
		(33 "B.Fab" user "Ref Des/Assembly Bottom")
	)
	(footprint ""
		(layer "F.Cu")
		(at 234.739688 -159.997648 180)
		(property "Reference" "U154"
			(at -4.057904 -1.950212 0)
			(unlocked yes)
			(layer "F.SilkS")
			(effects
				(font
					(size 0.7874 0.5842)
					(thickness 0.1524)
				)
				(justify left)
			)
		)
		(property "Value" ""
			(at 0 0 180)
			(layer "F.Fab")
			(effects
				(font
					(size 1.27 1.27)
				)
			)
		)
		(duplicate_pad_numbers_are_jumpers no)
		(fp_line
			(start 1.0414 1.575054)
			(end -1.0414 1.575054)
			(stroke
				(width 0.1524)
				(type default)
			)
			(layer "F.SilkS")
		)
		(fp_line
			(start 1.0414 -1.575054)
			(end 1.0414 1.575054)
			(stroke
				(width 0.1524)
				(type default)
			)
			(layer "F.SilkS")
		)
		(fp_line
			(start 0.254 -1.575054)
			(end 1.0414 -1.575054)
			(stroke
				(width 0.1524)
				(type default)
			)
			(layer "F.SilkS")
		)
		(fp_line
			(start 0.2286 -1.575054)
			(end 0 -1.272032)
			(stroke
				(width 0.1524)
				(type default)
			)
			(layer "F.SilkS")
		)
		(fp_line
			(start 0 -1.272032)
			(end -0.254 -1.575054)
			(stroke
				(width 0.1524)
				(type default)
			)
			(layer "F.SilkS")
		)
		(fp_line
			(start -1.0414 1.575054)
			(end -1.0414 -1.575054)
			(stroke
				(width 0.1524)
				(type default)
			)
			(layer "F.SilkS")
		)
		(fp_line
			(start -1.0414 -1.575054)
			(end -0.254 -1.575054)
			(stroke
				(width 0.1524)
				(type default)
			)
			(layer "F.SilkS")
		)
		(fp_poly
			(pts
				(xy -3.443224 -1.397254) (xy -2.598928 -0.975106) (xy -3.443224 -0.552958)
			)
			(stroke
				(width 0)
				(type default)
			)
			(fill yes)
			(layer "F.SilkS")
		)
		(fp_line
			(start 2.5654 1.2192)
			(end 1.4478 1.2192)
			(stroke
				(width 0.1)
				(type default)
			)
			(layer "F.Fab")
		)
		(fp_line
			(start 2.5654 -1.2192)
			(end 2.5654 1.2192)
			(stroke
				(width 0.1)
				(type default)
			)
			(layer "F.Fab")
		)
		(fp_line
			(start 1.4478 1.5748)
			(end -1.4478 1.5748)
			(stroke
				(width 0.1)
				(type default)
			)
			(layer "F.Fab")
		)
		(fp_line
			(start 1.4478 1.2192)
			(end 1.4478 1.5748)
			(stroke
				(width 0.1)
				(type default)
			)
			(layer "F.Fab")
		)
		(fp_line
			(start 1.4478 -1.2192)
			(end 2.5654 -1.2192)
			(stroke
				(width 0.1)
				(type default)
			)
			(layer "F.Fab")
		)
		(fp_line
			(start 1.4478 -1.5748)
			(end 1.4478 -1.2192)
			(stroke
				(width 0.1)
				(type default)
			)
			(layer "F.Fab")
		)
		(fp_line
			(start -1.4478 1.5748)
			(end -1.4478 1.2192)
			(stroke
				(width 0.1)
				(type default)
			)
			(layer "F.Fab")
		)
		(fp_line
			(start -1.4478 1.2192)
			(end -2.5654 1.2192)
			(stroke
				(width 0.1)
				(type default)
			)
			(layer "F.Fab")
		)
		(fp_line
			(start -1.4478 -1.2192)
			(end -1.4478 -1.5748)
			(stroke
				(width 0.1)
				(type default)
			)
			(layer "F.Fab")
		)
		(fp_line
			(start -1.4478 -1.5748)
			(end 1.4478 -1.5748)
			(stroke
				(width 0.1)
				(type default)
			)
			(layer "F.Fab")
		)
		(fp_line
			(start -2.5654 1.2192)
			(end -2.5654 -1.2192)
			(stroke
				(width 0.1)
				(type default)
			)
			(layer "F.Fab")
		)
		(fp_line
			(start -2.5654 -1.2192)
			(end -1.4478 -1.2192)
			(stroke
				(width 0.1)
				(type default)
			)
			(layer "F.Fab")
		)
		(fp_poly
			(pts
				(xy -2.710688 -0.975106) (xy -3.726688 -1.483106) (xy -3.726688 -0.467106)
			)
			(stroke
				(width 0)
				(type default)
			)
			(fill yes)
			(layer "F.Fab")
		)
		(pad "1" smd rect
			(at -1.849882 -0.975106 90)
			(size 0.3556 1.3208)
			(layers "F.Cu" "F.Mask" "F.Paste")
			(net "JTAG_CPU1_TDO")
		)
		(pad "2" smd rect
			(at -1.849882 -0.32512 90)
			(size 0.3556 1.3208)
			(layers "F.Cu" "F.Mask" "F.Paste")
			(net "JTAG_CPUX_TDO_R")
		)
		(pad "3" smd rect
			(at -1.849882 0.32512 90)
			(size 0.3556 1.3208)
			(layers "F.Cu" "F.Mask" "F.Paste")
			(net "FM_PLD_CPU1_PRSNT_HDT_N")
		)
		(pad "4" smd rect
			(at -1.849882 0.975106 90)
			(size 0.3556 1.3208)
			(layers "F.Cu" "F.Mask" "F.Paste")
			(net "GND")
		)
		(pad "5" smd rect
			(at 1.849882 0.975106 90)
			(size 0.3556 1.3208)
			(layers "F.Cu" "F.Mask" "F.Paste")
			(net "JTAG_CPU1_BYPASS")
		)
		(pad "6" smd rect
			(at 1.849882 0.32512 90)
			(size 0.3556 1.3208)
			(layers "F.Cu" "F.Mask" "F.Paste")
			(net "JTAG_CPUX_TDO_R")
		)
		(pad "7" smd rect
			(at 1.849882 -0.32512 90)
			(size 0.3556 1.3208)
			(layers "F.Cu" "F.Mask" "F.Paste")
			(net "CPU1_HDT_BYPASS_SEL")
		)
		(pad "8" smd rect
			(at 1.849882 -0.975106 90)
			(size 0.3556 1.3208)
			(layers "F.Cu" "F.Mask" "F.Paste")
			(net "PVDD18_S5_P0")
		)
	)
	(footprint ""
		(layer "F.Cu")
		(at 272.728182 -351.573846 90)
		(property "Reference" "PC176_10"
			(at 0 0 90)
			(layer "F.SilkS")
			(hide yes)
			(effects
				(font
					(size 1.27 1.27)
				)
			)
		)
		(property "Value" ""
			(at 0 0 90)
			(layer "F.Fab")
			(effects
				(font
					(size 1.27 1.27)
				)
			)
		)
		(duplicate_pad_numbers_are_jumpers no)
		(fp_line
			(start 0.7874 -0.4064)
			(end 0.7874 0.4064)
			(stroke
				(width 0.1524)
				(type default)
			)
			(layer "F.SilkS")
		)
		(fp_line
			(start -0.7874 -0.4064)
			(end 0.7874 -0.4064)
			(stroke
				(width 0.1524)
				(type default)
			)
			(layer "F.SilkS")
		)
		(fp_line
			(start 0.7874 0.4064)
			(end -0.7874 0.4064)
			(stroke
				(width 0.1524)
				(type default)
			)
			(layer "F.SilkS")
		)
		(fp_line
			(start -0.7874 0.4064)
			(end -0.7874 -0.4064)
			(stroke
				(width 0.1524)
				(type default)
			)
			(layer "F.SilkS")
		)
		(fp_line
			(start -0.12065 -0.305054)
			(end -0.12065 -0.2794)
			(stroke
				(width 0.1)
				(type default)
			)
			(layer "F.Fab")
		)
		(fp_line
			(start -0.67945 -0.305054)
			(end -0.12065 -0.305054)
			(stroke
				(width 0.1)
				(type default)
			)
			(layer "F.Fab")
		)
		(fp_line
			(start 0.67945 -0.3048)
			(end 0.67945 0.3048)
			(stroke
				(width 0.1)
				(type default)
			)
			(layer "F.Fab")
		)
		(fp_line
			(start 0.12065 -0.3048)
			(end 0.67945 -0.3048)
			(stroke
				(width 0.1)
				(type default)
			)
			(layer "F.Fab")
		)
		(fp_line
			(start 0.12065 -0.2794)
			(end 0.12065 -0.3048)
			(stroke
				(width 0.1)
				(type default)
			)
			(layer "F.Fab")
		)
		(fp_line
			(start -0.12065 -0.2794)
			(end 0.12065 -0.2794)
			(stroke
				(width 0.1)
				(type default)
			)
			(layer "F.Fab")
		)
		(fp_line
			(start 0.120396 0.2794)
			(end -0.12065 0.2794)
			(stroke
				(width 0.1)
				(type default)
			)
			(layer "F.Fab")
		)
		(fp_line
			(start -0.12065 0.2794)
			(end -0.12065 0.3048)
			(stroke
				(width 0.1)
				(type default)
			)
			(layer "F.Fab")
		)
		(fp_line
			(start 0.67945 0.3048)
			(end 0.120396 0.3048)
			(stroke
				(width 0.1)
				(type default)
			)
			(layer "F.Fab")
		)
		(fp_line
			(start 0.120396 0.3048)
			(end 0.120396 0.2794)
			(stroke
				(width 0.1)
				(type default)
			)
			(layer "F.Fab")
		)
		(fp_line
			(start -0.12065 0.3048)
			(end -0.67945 0.3048)
			(stroke
				(width 0.1)
				(type default)
			)
			(layer "F.Fab")
		)
		(fp_line
			(start -0.67945 0.3048)
			(end -0.67945 -0.305054)
			(stroke
				(width 0.1)
				(type default)
			)
			(layer "F.Fab")
		)
		(pad "1" smd circle
			(at -0.40005 0 90)
			(size 0 0)
			(layers "F.Cu" "F.Mask" "F.Paste")
			(net "PVDDCR_CPU1_P0_VCCS")
		)
		(pad "2" smd circle
			(at 0.40005 0 90)
			(size 0 0)
			(layers "F.Cu" "F.Mask" "F.Paste")
			(net "GND")
		)
	)
)
